(kicad_pcb
	(version 20260206)
	(generator "pcbnew")
	(generator_version "10.0")
	(general
		(thickness 1.6)
		(legacy_teardrops no)
	)
	(paper "A4")
	(title_block
		(title "Wiwynn_Tioga_Pass_MB.brd")
		(comment 1 "Tioga Pass / footprints 4336-4342 of 4770")
	)
	(layers
		(0 "F.Cu" signal "TOP")
		(4 "In1.Cu" signal "L2GND")
		(6 "In2.Cu" signal "L3")
		(8 "In3.Cu" signal "L4GND")
		(10 "In4.Cu" signal "L5")
		(12 "In5.Cu" signal "L6GND")
		(14 "In6.Cu" signal "L7VCC")
		(16 "In7.Cu" signal "L8VCC")
		(18 "In8.Cu" signal "L9GND")
		(20 "In9.Cu" signal "L10")
		(22 "In10.Cu" signal "L11GND")
		(24 "In11.Cu" signal "L12")
		(26 "In12.Cu" signal "L13GND")
		(2 "B.Cu" signal "BOTTOM")
		(9 "F.Adhes" user "F.Adhesive")
		(11 "B.Adhes" user "B.Adhesive")
		(13 "F.Paste" user "Package Geometry/Pastemask Top")
		(15 "B.Paste" user "Package Geometry/Pastemask Bottom")
		(5 "F.SilkS" user "Ref Des/Silkscreen Top")
		(7 "B.SilkS" user "Ref Des/Silkscreen Bottom")
		(1 "F.Mask" user "Board Geometry/Soldermask Top")
		(3 "B.Mask" user "Board Geometry/Soldermask Bottom")
		(17 "Dwgs.User" user "User.Drawings")
		(19 "Cmts.User" user "User.Comments")
		(21 "Eco1.User" user "User.Eco1")
		(23 "Eco2.User" user "User.Eco2")
		(25 "Edge.Cuts" user "Board Geometry/Outline")
		(27 "Margin" user)
		(31 "F.CrtYd" user "Package Geometry/Place Bound Top")
		(29 "B.CrtYd" user "Package Geometry/Place Bound Bottom")
		(35 "F.Fab" user "Ref Des/Assembly Top")
		(33 "B.Fab" user "Ref Des/Assembly Bottom")
	)
	(footprint ""
		(layer "B.Cu")
		(at 27.023568 -134.874 180)
		(property "Reference" "C9M2"
			(at 0 0 0)
			(layer "B.SilkS")
			(hide yes)
			(effects
				(font
					(size 1.27 1.27)
				)
				(justify mirror)
			)
		)
		(property "Value" ""
			(at 0 0 0)
			(layer "B.Fab")
			(effects
				(font
					(size 1.27 1.27)
				)
				(justify mirror)
			)
		)
		(duplicate_pad_numbers_are_jumpers no)
		(fp_poly
			(pts
				(xy -0.3048 -0.1016) (xy -0.3048 0.9906) (xy 0.3048 0.9906) (xy 0.3048 -0.1016)
			)
			(stroke
				(width 0)
				(type default)
			)
			(fill no)
			(layer "B.CrtYd")
		)
		(fp_line
			(start 0.3048 0.9906)
			(end -0.3048 0.9906)
			(stroke
				(width 0.1)
				(type default)
			)
			(layer "B.Fab")
		)
		(fp_line
			(start 0.3048 -0.1016)
			(end 0.3048 0.9906)
			(stroke
				(width 0.1)
				(type default)
			)
			(layer "B.Fab")
		)
		(fp_line
			(start -0.3048 0.9906)
			(end -0.3048 -0.1016)
			(stroke
				(width 0.1)
				(type default)
			)
			(layer "B.Fab")
		)
		(fp_line
			(start -0.3048 -0.1016)
			(end 0.3048 -0.1016)
			(stroke
				(width 0.1)
				(type default)
			)
			(layer "B.Fab")
		)
		(pad "1" smd rect
			(at 0 0)
			(size 0.508 0.508)
			(layers "B.Cu" "B.Mask" "B.Paste")
			(net "M_K_CPU_VREF")
		)
		(pad "2" smd rect
			(at 0 0.889)
			(size 0.508 0.508)
			(layers "B.Cu" "B.Mask" "B.Paste")
			(net "GND")
		)
		(zone
			(layer "B.Cu")
			(hatch none 0.5)
			(connect_pads
				(clearance 0)
			)
			(min_thickness 0.25)
			(keepout
				(tracks not_allowed)
				(vias allowed)
				(pads allowed)
				(copperpour not_allowed)
				(footprints allowed)
			)
			(placement
				(enabled no)
				(sheetname "")
			)
			(fill
				(thermal_gap 0.5)
				(thermal_bridge_width 0.5)
				(island_removal_mode 0)
			)
			(polygon
				(pts
					(xy 26.769568 -135.509) (xy 27.277568 -135.509) (xy 27.277568 -135.128) (xy 26.769568 -135.128)
				)
			)
		)
		(zone
			(layer "B.Cu")
			(hatch none 0.5)
			(connect_pads
				(clearance 0)
			)
			(min_thickness 0.25)
			(keepout
				(tracks allowed)
				(vias not_allowed)
				(pads allowed)
				(copperpour not_allowed)
				(footprints allowed)
			)
			(placement
				(enabled no)
				(sheetname "")
			)
			(fill
				(thermal_gap 0.5)
				(thermal_bridge_width 0.5)
				(island_removal_mode 0)
			)
			(polygon
				(pts
					(xy 26.769568 -135.128) (xy 27.277568 -135.128) (xy 27.277568 -135.509) (xy 26.769568 -135.509)
				)
			)
		)
	)
	(footprint ""
		(layer "B.Cu")
		(at 385.90474 -83.22056 90)
		(property "Reference" "C14W1"
			(at 0.8382 -0.67818 90)
			(unlocked yes)
			(layer "B.SilkS")
			(effects
				(font
					(size 0.4064 0.254)
					(thickness 0.1524)
				)
				(justify left mirror)
			)
		)
		(property "Value" ""
			(at 0 0 90)
			(layer "B.Fab")
			(effects
				(font
					(size 1.27 1.27)
				)
				(justify mirror)
			)
		)
		(duplicate_pad_numbers_are_jumpers no)
		(fp_poly
			(pts
				(xy -0.3048 -0.1016) (xy -0.3048 0.9906) (xy 0.3048 0.9906) (xy 0.3048 -0.1016)
			)
			(stroke
				(width 0)
				(type default)
			)
			(fill no)
			(layer "B.CrtYd")
		)
		(fp_line
			(start 0.3048 -0.1016)
			(end 0.3048 0.9906)
			(stroke
				(width 0.1)
				(type default)
			)
			(layer "B.Fab")
		)
		(fp_line
			(start -0.3048 -0.1016)
			(end 0.3048 -0.1016)
			(stroke
				(width 0.1)
				(type default)
			)
			(layer "B.Fab")
		)
		(fp_line
			(start 0.3048 0.9906)
			(end -0.3048 0.9906)
			(stroke
				(width 0.1)
				(type default)
			)
			(layer "B.Fab")
		)
		(fp_line
			(start -0.3048 0.9906)
			(end -0.3048 -0.1016)
			(stroke
				(width 0.1)
				(type default)
			)
			(layer "B.Fab")
		)
		(pad "1" smd rect
			(at 0 0 270)
			(size 0.508 0.508)
			(layers "B.Cu" "B.Mask" "B.Paste")
			(net "P3V3")
		)
		(pad "2" smd rect
			(at 0 0.889 270)
			(size 0.508 0.508)
			(layers "B.Cu" "B.Mask" "B.Paste")
			(net "GND")
		)
		(zone
			(layer "B.Cu")
			(hatch none 0.5)
			(connect_pads
				(clearance 0)
			)
			(min_thickness 0.25)
			(keepout
				(tracks allowed)
				(vias not_allowed)
				(pads allowed)
				(copperpour not_allowed)
				(footprints allowed)
			)
			(placement
				(enabled no)
				(sheetname "")
			)
			(fill
				(thermal_gap 0.5)
				(thermal_bridge_width 0.5)
				(island_removal_mode 0)
			)
			(polygon
				(pts
					(xy 386.15874 -83.47456) (xy 386.15874 -82.96656) (xy 386.53974 -82.96656) (xy 386.53974 -83.47456)
				)
			)
		)
		(zone
			(layer "B.Cu")
			(hatch none 0.5)
			(connect_pads
				(clearance 0)
			)
			(min_thickness 0.25)
			(keepout
				(tracks not_allowed)
				(vias allowed)
				(pads allowed)
				(copperpour not_allowed)
				(footprints allowed)
			)
			(placement
				(enabled no)
				(sheetname "")
			)
			(fill
				(thermal_gap 0.5)
				(thermal_bridge_width 0.5)
				(island_removal_mode 0)
			)
			(polygon
				(pts
					(xy 386.53974 -83.47456) (xy 386.53974 -82.96656) (xy 386.15874 -82.96656) (xy 386.15874 -83.47456)
				)
			)
		)
	)
	(footprint ""
		(layer "B.Cu")
		(at 401.193 -107.1245 180)
		(property "Reference" "R8C6"
			(at 0 0 0)
			(layer "B.SilkS")
			(hide yes)
			(effects
				(font
					(size 1.27 1.27)
				)
				(justify mirror)
			)
		)
		(property "Value" ""
			(at 0 0 0)
			(layer "B.Fab")
			(effects
				(font
					(size 1.27 1.27)
				)
				(justify mirror)
			)
		)
		(duplicate_pad_numbers_are_jumpers no)
		(fp_poly
			(pts
				(xy 0.2794 -0.1016) (xy -0.2794 -0.1016) (xy -0.2794 0.9906) (xy 0.2794 0.9906)
			)
			(stroke
				(width 0)
				(type default)
			)
			(fill no)
			(layer "B.CrtYd")
		)
		(fp_line
			(start 0.2794 0.9906)
			(end -0.2794 0.9906)
			(stroke
				(width 0.1)
				(type default)
			)
			(layer "B.Fab")
		)
		(fp_line
			(start 0.2794 -0.1016)
			(end 0.2794 0.9906)
			(stroke
				(width 0.1)
				(type default)
			)
			(layer "B.Fab")
		)
		(fp_line
			(start -0.2794 0.9906)
			(end -0.2794 -0.1016)
			(stroke
				(width 0.1)
				(type default)
			)
			(layer "B.Fab")
		)
		(fp_line
			(start -0.2794 -0.1016)
			(end 0.2794 -0.1016)
			(stroke
				(width 0.1)
				(type default)
			)
			(layer "B.Fab")
		)
		(pad "1" smd rect
			(at 0 0)
			(size 0.508 0.508)
			(layers "B.Cu" "B.Mask" "B.Paste")
			(net "P3V3_STBY")
		)
		(pad "2" smd rect
			(at 0 0.889)
			(size 0.508 0.508)
			(layers "B.Cu" "B.Mask" "B.Paste")
			(net "FM_BIOS_POST_CMPLT_N")
		)
		(zone
			(layer "B.Cu")
			(hatch none 0.5)
			(connect_pads
				(clearance 0)
			)
			(min_thickness 0.25)
			(keepout
				(tracks not_allowed)
				(vias allowed)
				(pads allowed)
				(copperpour not_allowed)
				(footprints allowed)
			)
			(placement
				(enabled no)
				(sheetname "")
			)
			(fill
				(thermal_gap 0.5)
				(thermal_bridge_width 0.5)
				(island_removal_mode 0)
			)
			(polygon
				(pts
					(xy 400.939 -107.7595) (xy 401.447 -107.7595) (xy 401.447 -107.3785) (xy 400.939 -107.3785)
				)
			)
		)
		(zone
			(layer "B.Cu")
			(hatch none 0.5)
			(connect_pads
				(clearance 0)
			)
			(min_thickness 0.25)
			(keepout
				(tracks allowed)
				(vias not_allowed)
				(pads allowed)
				(copperpour not_allowed)
				(footprints allowed)
			)
			(placement
				(enabled no)
				(sheetname "")
			)
			(fill
				(thermal_gap 0.5)
				(thermal_bridge_width 0.5)
				(island_removal_mode 0)
			)
			(polygon
				(pts
					(xy 400.939 -107.3785) (xy 401.447 -107.3785) (xy 401.447 -107.7595) (xy 400.939 -107.7595)
				)
			)
		)
	)
	(footprint ""
		(layer "B.Cu")
		(at 398.272 -27.432 180)
		(property "Reference" "R2T34"
			(at 0 0 0)
			(layer "B.SilkS")
			(hide yes)
			(effects
				(font
					(size 1.27 1.27)
				)
				(justify mirror)
			)
		)
		(property "Value" ""
			(at 0 0 0)
			(layer "B.Fab")
			(effects
				(font
					(size 1.27 1.27)
				)
				(justify mirror)
			)
		)
		(duplicate_pad_numbers_are_jumpers no)
		(fp_poly
			(pts
				(xy 0.2794 -0.1016) (xy -0.2794 -0.1016) (xy -0.2794 0.9906) (xy 0.2794 0.9906)
			)
			(stroke
				(width 0)
				(type default)
			)
			(fill no)
			(layer "B.CrtYd")
		)
		(fp_line
			(start 0.2794 0.9906)
			(end -0.2794 0.9906)
			(stroke
				(width 0.1)
				(type default)
			)
			(layer "B.Fab")
		)
		(fp_line
			(start 0.2794 -0.1016)
			(end 0.2794 0.9906)
			(stroke
				(width 0.1)
				(type default)
			)
			(layer "B.Fab")
		)
		(fp_line
			(start -0.2794 0.9906)
			(end -0.2794 -0.1016)
			(stroke
				(width 0.1)
				(type default)
			)
			(layer "B.Fab")
		)
		(fp_line
			(start -0.2794 -0.1016)
			(end 0.2794 -0.1016)
			(stroke
				(width 0.1)
				(type default)
			)
			(layer "B.Fab")
		)
		(pad "1" smd rect
			(at 0 0)
			(size 0.508 0.508)
			(layers "B.Cu" "B.Mask" "B.Paste")
			(net "P3V3_STBY")
		)
		(pad "2" smd rect
			(at 0 0.889)
			(size 0.508 0.508)
			(layers "B.Cu" "B.Mask" "B.Paste")
			(net "FM_BMC_PWRBTN_OUT_N")
		)
		(zone
			(layer "B.Cu")
			(hatch none 0.5)
			(connect_pads
				(clearance 0)
			)
			(min_thickness 0.25)
			(keepout
				(tracks not_allowed)
				(vias allowed)
				(pads allowed)
				(copperpour not_allowed)
				(footprints allowed)
			)
			(placement
				(enabled no)
				(sheetname "")
			)
			(fill
				(thermal_gap 0.5)
				(thermal_bridge_width 0.5)
				(island_removal_mode 0)
			)
			(polygon
				(pts
					(xy 398.018 -28.067) (xy 398.526 -28.067) (xy 398.526 -27.686) (xy 398.018 -27.686)
				)
			)
		)
		(zone
			(layer "B.Cu")
			(hatch none 0.5)
			(connect_pads
				(clearance 0)
			)
			(min_thickness 0.25)
			(keepout
				(tracks allowed)
				(vias not_allowed)
				(pads allowed)
				(copperpour not_allowed)
				(footprints allowed)
			)
			(placement
				(enabled no)
				(sheetname "")
			)
			(fill
				(thermal_gap 0.5)
				(thermal_bridge_width 0.5)
				(island_removal_mode 0)
			)
			(polygon
				(pts
					(xy 398.018 -27.686) (xy 398.526 -27.686) (xy 398.526 -28.067) (xy 398.018 -28.067)
				)
			)
		)
	)
	(footprint ""
		(layer "B.Cu")
		(at 370.745258 -75.494642 180)
		(property "Reference" "C3P43"
			(at 0 0 0)
			(layer "B.SilkS")
			(hide yes)
			(effects
				(font
					(size 1.27 1.27)
				)
				(justify mirror)
			)
		)
		(property "Value" ""
			(at 0 0 0)
			(layer "B.Fab")
			(effects
				(font
					(size 1.27 1.27)
				)
				(justify mirror)
			)
		)
		(duplicate_pad_numbers_are_jumpers no)
		(fp_rect
			(start 0.2794 0.9144)
			(end -0.2794 -0.1143)
			(stroke
				(width 0)
				(type default)
			)
			(fill no)
			(layer "B.CrtYd")
		)
		(fp_line
			(start 0.2794 0.9144)
			(end 0.2794 -0.1143)
			(stroke
				(width 0.1)
				(type default)
			)
			(layer "B.Fab")
		)
		(fp_line
			(start 0.2794 -0.1143)
			(end -0.2794 -0.1143)
			(stroke
				(width 0.1)
				(type default)
			)
			(layer "B.Fab")
		)
		(fp_line
			(start -0.2794 0.9144)
			(end 0.2794 0.9144)
			(stroke
				(width 0.1)
				(type default)
			)
			(layer "B.Fab")
		)
		(fp_line
			(start -0.2794 -0.1143)
			(end -0.2794 0.9144)
			(stroke
				(width 0.1)
				(type default)
			)
			(layer "B.Fab")
		)
		(pad "1" smd custom
			(at 0 0 90)
			(size 0.10414 0.10414)
			(layers "B.Cu" "B.Mask" "B.Paste")
			(net "P3V3_STBY")
			(options
				(clearance outline)
				(anchor circle)
			)
			(primitives
				(gr_poly
					(pts
						(xy -0.20828 -0.08636) (xy -0.20828 0.08636) (xy -0.08636 0.20828) (xy 0.086614 0.20828) (xy 0.20828 0.086614)
						(xy 0.20828 -0.08636) (xy 0.08636 -0.20828) (xy -0.08636 -0.20828)
					)
					(width 0)
					(fill yes)
				)
			)
		)
		(pad "2" smd custom
			(at 0 0.8001 90)
			(size 0.10414 0.10414)
			(layers "B.Cu" "B.Mask" "B.Paste")
			(net "GND")
			(options
				(clearance outline)
				(anchor circle)
			)
			(primitives
				(gr_poly
					(pts
						(xy -0.20828 -0.08636) (xy -0.20828 0.08636) (xy -0.08636 0.20828) (xy 0.086614 0.20828) (xy 0.20828 0.086614)
						(xy 0.20828 -0.08636) (xy 0.08636 -0.20828) (xy -0.08636 -0.20828)
					)
					(width 0)
					(fill yes)
				)
			)
		)
		(zone
			(layer "B.Cu")
			(hatch none 0.5)
			(connect_pads
				(clearance 0)
			)
			(min_thickness 0.25)
			(keepout
				(tracks not_allowed)
				(vias allowed)
				(pads allowed)
				(copperpour not_allowed)
				(footprints allowed)
			)
			(placement
				(enabled no)
				(sheetname "")
			)
			(fill
				(thermal_gap 0.5)
				(thermal_bridge_width 0.5)
				(island_removal_mode 0)
			)
			(polygon
				(pts
					(xy 370.657628 -75.704192) (xy 370.657628 -76.085192) (xy 370.832888 -76.085192) (xy 370.833142 -75.704192)
				)
			)
		)
		(zone
			(layer "B.Cu")
			(hatch none 0.5)
			(connect_pads
				(clearance 0)
			)
			(min_thickness 0.25)
			(keepout
				(tracks allowed)
				(vias not_allowed)
				(pads allowed)
				(copperpour not_allowed)
				(footprints allowed)
			)
			(placement
				(enabled no)
				(sheetname "")
			)
			(fill
				(thermal_gap 0.5)
				(thermal_bridge_width 0.5)
				(island_removal_mode 0)
			)
			(polygon
				(pts
					(xy 370.657628 -75.704192) (xy 370.657628 -76.085192) (xy 370.832888 -76.085192) (xy 370.833142 -75.704192)
				)
			)
		)
	)
	(footprint ""
		(layer "B.Cu")
		(at 350.110806 -60.368434)
		(property "Reference" "R2U26"
			(at 0 0 0)
			(layer "B.SilkS")
			(hide yes)
			(effects
				(font
					(size 1.27 1.27)
				)
				(justify mirror)
			)
		)
		(property "Value" ""
			(at 0 0 0)
			(layer "B.Fab")
			(effects
				(font
					(size 1.27 1.27)
				)
				(justify mirror)
			)
		)
		(duplicate_pad_numbers_are_jumpers no)
		(fp_poly
			(pts
				(xy 0.2794 -0.1016) (xy -0.2794 -0.1016) (xy -0.2794 0.9906) (xy 0.2794 0.9906)
			)
			(stroke
				(width 0)
				(type default)
			)
			(fill no)
			(layer "B.CrtYd")
		)
		(fp_line
			(start -0.2794 -0.1016)
			(end 0.2794 -0.1016)
			(stroke
				(width 0.1)
				(type default)
			)
			(layer "B.Fab")
		)
		(fp_line
			(start -0.2794 0.9906)
			(end -0.2794 -0.1016)
			(stroke
				(width 0.1)
				(type default)
			)
			(layer "B.Fab")
		)
		(fp_line
			(start 0.2794 -0.1016)
			(end 0.2794 0.9906)
			(stroke
				(width 0.1)
				(type default)
			)
			(layer "B.Fab")
		)
		(fp_line
			(start 0.2794 0.9906)
			(end -0.2794 0.9906)
			(stroke
				(width 0.1)
				(type default)
			)
			(layer "B.Fab")
		)
		(pad "1" smd rect
			(at 0 0 180)
			(size 0.508 0.508)
			(layers "B.Cu" "B.Mask" "B.Paste")
			(net "P3E_CPU0_PE1_SS_RXP<6>")
		)
		(pad "2" smd rect
			(at 0 0.889 180)
			(size 0.508 0.508)
			(layers "B.Cu" "B.Mask" "B.Paste")
			(net "P3E_CPU0_PE1_SS_R_RXP<6>")
		)
		(zone
			(layer "B.Cu")
			(hatch none 0.5)
			(connect_pads
				(clearance 0)
			)
			(min_thickness 0.25)
			(keepout
				(tracks allowed)
				(vias not_allowed)
				(pads allowed)
				(copperpour not_allowed)
				(footprints allowed)
			)
			(placement
				(enabled no)
				(sheetname "")
			)
			(fill
				(thermal_gap 0.5)
				(thermal_bridge_width 0.5)
				(island_removal_mode 0)
			)
			(polygon
				(pts
					(xy 350.364806 -60.114434) (xy 349.856806 -60.114434) (xy 349.856806 -59.733434) (xy 350.364806 -59.733434)
				)
			)
		)
		(zone
			(layer "B.Cu")
			(hatch none 0.5)
			(connect_pads
				(clearance 0)
			)
			(min_thickness 0.25)
			(keepout
				(tracks not_allowed)
				(vias allowed)
				(pads allowed)
				(copperpour not_allowed)
				(footprints allowed)
			)
			(placement
				(enabled no)
				(sheetname "")
			)
			(fill
				(thermal_gap 0.5)
				(thermal_bridge_width 0.5)
				(island_removal_mode 0)
			)
			(polygon
				(pts
					(xy 350.364806 -59.733434) (xy 349.856806 -59.733434) (xy 349.856806 -60.114434) (xy 350.364806 -60.114434)
				)
			)
		)
	)
	(footprint ""
		(layer "B.Cu")
		(at 343.125806 -61.257434)
		(property "Reference" "C2U10"
			(at 0 0 0)
			(layer "B.SilkS")
			(hide yes)
			(effects
				(font
					(size 1.27 1.27)
				)
				(justify mirror)
			)
		)
		(property "Value" ""
			(at 0 0 0)
			(layer "B.Fab")
			(effects
				(font
					(size 1.27 1.27)
				)
				(justify mirror)
			)
		)
		(duplicate_pad_numbers_are_jumpers no)
		(fp_poly
			(pts
				(xy -0.3048 -0.1016) (xy -0.3048 0.9906) (xy 0.3048 0.9906) (xy 0.3048 -0.1016)
			)
			(stroke
				(width 0)
				(type default)
			)
			(fill no)
			(layer "B.CrtYd")
		)
		(fp_line
			(start -0.3048 -0.1016)
			(end 0.3048 -0.1016)
			(stroke
				(width 0.1)
				(type default)
			)
			(layer "B.Fab")
		)
		(fp_line
			(start -0.3048 0.9906)
			(end -0.3048 -0.1016)
			(stroke
				(width 0.1)
				(type default)
			)
			(layer "B.Fab")
		)
		(fp_line
			(start 0.3048 -0.1016)
			(end 0.3048 0.9906)
			(stroke
				(width 0.1)
				(type default)
			)
			(layer "B.Fab")
		)
		(fp_line
			(start 0.3048 0.9906)
			(end -0.3048 0.9906)
			(stroke
				(width 0.1)
				(type default)
			)
			(layer "B.Fab")
		)
		(pad "1" smd rect
			(at 0 0 180)
			(size 0.508 0.508)
			(layers "B.Cu" "B.Mask" "B.Paste")
			(net "P3E_CPU0_PE1_PCH_RXN<3>")
		)
		(pad "2" smd rect
			(at 0 0.889 180)
			(size 0.508 0.508)
			(layers "B.Cu" "B.Mask" "B.Paste")
			(net "P3E_CPU0_PE1_SS_RXN<3>")
		)
		(zone
			(layer "B.Cu")
			(hatch none 0.5)
			(connect_pads
				(clearance 0)
			)
			(min_thickness 0.25)
			(keepout
				(tracks allowed)
				(vias not_allowed)
				(pads allowed)
				(copperpour not_allowed)
				(footprints allowed)
			)
			(placement
				(enabled no)
				(sheetname "")
			)
			(fill
				(thermal_gap 0.5)
				(thermal_bridge_width 0.5)
				(island_removal_mode 0)
			)
			(polygon
				(pts
					(xy 343.379806 -61.003434) (xy 342.871806 -61.003434) (xy 342.871806 -60.622434) (xy 343.379806 -60.622434)
				)
			)
		)
		(zone
			(layer "B.Cu")
			(hatch none 0.5)
			(connect_pads
				(clearance 0)
			)
			(min_thickness 0.25)
			(keepout
				(tracks not_allowed)
				(vias allowed)
				(pads allowed)
				(copperpour not_allowed)
				(footprints allowed)
			)
			(placement
				(enabled no)
				(sheetname "")
			)
			(fill
				(thermal_gap 0.5)
				(thermal_bridge_width 0.5)
				(island_removal_mode 0)
			)
			(polygon
				(pts
					(xy 343.379806 -60.622434) (xy 342.871806 -60.622434) (xy 342.871806 -61.003434) (xy 343.379806 -61.003434)
				)
			)
		)
	)
)
